(kicad_pcb
	(version 20260206)
	(generator "pcbnew")
	(generator_version "10.0")
	(general
		(thickness 1.6)
		(legacy_teardrops no)
	)
	(paper "A4")
	(title_block
		(title "04192023_DAF0TMB3IC0_F0TG_MB_C_brd_V02_OCP.brd")
		(comment 1 "Grand Teton / footprints 2554-2559 of 8354")
	)
	(layers
		(0 "F.Cu" signal "TOP")
		(4 "In1.Cu" signal "GND")
		(6 "In2.Cu" signal "IN1")
		(8 "In3.Cu" signal "GND1")
		(10 "In4.Cu" signal "IN2")
		(12 "In5.Cu" signal "GND2")
		(14 "In6.Cu" signal "IN3")
		(16 "In7.Cu" signal "GND3")
		(18 "In8.Cu" signal "VCC")
		(20 "In9.Cu" signal "VCC1")
		(22 "In10.Cu" signal "GND4")
		(24 "In11.Cu" signal "IN4")
		(26 "In12.Cu" signal "GND5")
		(28 "In13.Cu" signal "IN5")
		(30 "In14.Cu" signal "GND6")
		(32 "In15.Cu" signal "IN6")
		(34 "In16.Cu" signal "GND7")
		(2 "B.Cu" signal "BOTTOM")
		(9 "F.Adhes" user "F.Adhesive")
		(11 "B.Adhes" user "B.Adhesive")
		(13 "F.Paste" user "Package Geometry/Pastemask Top")
		(15 "B.Paste" user "Package Geometry/Pastemask Bottom")
		(5 "F.SilkS" user "Ref Des/Silkscreen Top")
		(7 "B.SilkS" user "Ref Des/Silkscreen Bottom")
		(1 "F.Mask" user "Board Geometry/Soldermask Top")
		(3 "B.Mask" user "Board Geometry/Soldermask Bottom")
		(17 "Dwgs.User" user "User.Drawings")
		(19 "Cmts.User" user "User.Comments")
		(21 "Eco1.User" user "User.Eco1")
		(23 "Eco2.User" user "User.Eco2")
		(25 "Edge.Cuts" user "Board Geometry/Outline")
		(27 "Margin" user)
		(31 "F.CrtYd" user "Package Geometry/Place Bound Top")
		(29 "B.CrtYd" user "Package Geometry/Place Bound Bottom")
		(35 "F.Fab" user "Ref Des/Assembly Top")
		(33 "B.Fab" user "Ref Des/Assembly Bottom")
	)
	(footprint ""
		(layer "F.Cu")
		(at 79.356458 -20.694142)
		(property "Reference" "PU201"
			(at 2.898394 -1.895856 0)
			(unlocked yes)
			(layer "F.SilkS")
			(effects
				(font
					(size 0.7874 0.5842)
					(thickness 0.1524)
				)
				(justify left)
			)
		)
		(property "Value" ""
			(at 0 0 0)
			(layer "F.Fab")
			(effects
				(font
					(size 1.27 1.27)
				)
			)
		)
		(duplicate_pad_numbers_are_jumpers no)
		(fp_line
			(start -1.774952 -1.039876)
			(end -1.774952 1.039876)
			(stroke
				(width 0.1524)
				(type default)
			)
			(layer "F.SilkS")
		)
		(fp_line
			(start -1.774952 1.039876)
			(end 1.774952 1.039876)
			(stroke
				(width 0.1524)
				(type default)
			)
			(layer "F.SilkS")
		)
		(fp_line
			(start 1.774952 -1.039876)
			(end -1.774952 -1.039876)
			(stroke
				(width 0.1524)
				(type default)
			)
			(layer "F.SilkS")
		)
		(fp_line
			(start 1.774952 1.039876)
			(end 1.774952 -1.039876)
			(stroke
				(width 0.1524)
				(type default)
			)
			(layer "F.SilkS")
		)
		(fp_poly
			(pts
				(xy -0.999998 -1.801876) (xy -0.999998 -1.039876) (xy -1.769872 -1.039876) (xy -1.769872 -0.249936)
				(xy -2.531872 -0.249936) (xy -2.531872 -1.801876)
			)
			(stroke
				(width 0)
				(type default)
			)
			(fill yes)
			(layer "F.SilkS")
		)
		(fp_line
			(start -1.769872 -1.039876)
			(end -1.769872 1.039876)
			(stroke
				(width 0.1)
				(type default)
			)
			(layer "F.Fab")
		)
		(fp_line
			(start -1.769872 1.039876)
			(end 1.769872 1.039876)
			(stroke
				(width 0.1)
				(type default)
			)
			(layer "F.Fab")
		)
		(fp_line
			(start 1.769872 -1.039876)
			(end -1.769872 -1.039876)
			(stroke
				(width 0.1)
				(type default)
			)
			(layer "F.Fab")
		)
		(fp_line
			(start 1.769872 1.039876)
			(end 1.769872 -1.039876)
			(stroke
				(width 0.1)
				(type default)
			)
			(layer "F.Fab")
		)
		(fp_poly
			(pts
				(xy -1.769872 -1.039876) (xy -0.999998 -1.039876) (xy -0.999998 -1.801876) (xy -2.531872 -1.801876)
				(xy -2.531872 -0.249936) (xy -1.769872 -0.249936)
			)
			(stroke
				(width 0)
				(type default)
			)
			(fill yes)
			(layer "F.Fab")
		)
		(pad "A1" smd circle
			(at -1.500124 -0.750062)
			(size 0.2286 0.2286)
			(layers "F.Cu" "F.Mask" "F.Paste")
			(net "P12V_OCP_SENSE_2")
		)
		(pad "A2" smd circle
			(at -0.999998 -0.750062)
			(size 0.2286 0.2286)
			(layers "F.Cu" "F.Mask" "F.Paste")
			(net "P12V_OCP_VCC_2")
		)
		(pad "A3" smd circle
			(at -0.499872 -0.750062)
			(size 0.2286 0.2286)
			(layers "F.Cu" "F.Mask" "F.Paste")
			(net "P12V_AUX")
		)
		(pad "A4" smd circle
			(at 0 -0.750062)
			(size 0.2286 0.2286)
			(layers "F.Cu" "F.Mask" "F.Paste")
			(net "P12V_OCP_V3_2")
		)
		(pad "A5" smd circle
			(at 0.499872 -0.750062)
			(size 0.2286 0.2286)
			(layers "F.Cu" "F.Mask" "F.Paste")
			(net "P12V_AUX")
		)
		(pad "A6" smd circle
			(at 0.999998 -0.750062)
			(size 0.2286 0.2286)
			(layers "F.Cu" "F.Mask" "F.Paste")
			(net "P12V_OCP_GATE_2")
		)
		(pad "A7" smd circle
			(at 1.500124 -0.750062)
			(size 0.2286 0.2286)
			(layers "F.Cu" "F.Mask" "F.Paste")
			(net "GND")
		)
		(pad "B1" smd circle
			(at -1.500124 -0.249936)
			(size 0.2286 0.2286)
			(layers "F.Cu" "F.Mask" "F.Paste")
			(net "P12V_OCP_CB_2")
		)
		(pad "B2" smd circle
			(at -0.999998 -0.249936)
			(size 0.2286 0.2286)
			(layers "F.Cu" "F.Mask" "F.Paste")
			(net "GND")
		)
		(pad "B3" smd circle
			(at -0.499872 -0.249936)
			(size 0.2286 0.2286)
			(layers "F.Cu" "F.Mask" "F.Paste")
			(net "P12V_AUX")
		)
		(pad "B4" smd circle
			(at 0 -0.249936)
			(size 0.2286 0.2286)
			(layers "F.Cu" "F.Mask" "F.Paste")
			(net "P12V_OCP_V3_2")
		)
		(pad "B5" smd circle
			(at 0.499872 -0.249936)
			(size 0.2286 0.2286)
			(layers "F.Cu" "F.Mask" "F.Paste")
			(net "P12V_AUX")
		)
		(pad "B6" smd circle
			(at 0.999998 -0.249936)
			(size 0.2286 0.2286)
			(layers "F.Cu" "F.Mask" "F.Paste")
			(net "P12V_OCP_V3_2")
		)
		(pad "B7" smd circle
			(at 1.500124 -0.249936)
			(size 0.2286 0.2286)
			(layers "F.Cu" "F.Mask" "F.Paste")
			(net "GND")
		)
		(pad "C1" smd circle
			(at -1.500124 0.249936)
			(size 0.2286 0.2286)
			(layers "F.Cu" "F.Mask" "F.Paste")
			(net "GND")
		)
		(pad "C2" smd circle
			(at -0.999998 0.249936)
			(size 0.2286 0.2286)
			(layers "F.Cu" "F.Mask" "F.Paste")
			(net "GND")
		)
		(pad "C3" smd circle
			(at -0.499872 0.249936)
			(size 0.2286 0.2286)
			(layers "F.Cu" "F.Mask" "F.Paste")
			(net "P12V_AUX")
		)
		(pad "C4" smd circle
			(at 0 0.249936)
			(size 0.2286 0.2286)
			(layers "F.Cu" "F.Mask" "F.Paste")
			(net "P12V_OCP_V3_2")
		)
		(pad "C5" smd circle
			(at 0.499872 0.249936)
			(size 0.2286 0.2286)
			(layers "F.Cu" "F.Mask" "F.Paste")
			(net "P12V_AUX")
		)
		(pad "C6" smd circle
			(at 0.999998 0.249936)
			(size 0.2286 0.2286)
			(layers "F.Cu" "F.Mask" "F.Paste")
			(net "P12V_OCP_V3_2")
		)
		(pad "C7" smd circle
			(at 1.500124 0.249936)
			(size 0.2286 0.2286)
			(layers "F.Cu" "F.Mask" "F.Paste")
			(net "P12V_OCP_FAULT_2")
		)
		(pad "D1" smd circle
			(at -1.500124 0.750062)
			(size 0.2286 0.2286)
			(layers "F.Cu" "F.Mask" "F.Paste")
			(net "P12V_OCP_REG_2")
		)
		(pad "D2" smd circle
			(at -0.999998 0.750062)
			(size 0.2286 0.2286)
			(layers "F.Cu" "F.Mask" "F.Paste")
			(net "P12V_OCP_UV_2")
		)
		(pad "D3" smd circle
			(at -0.499872 0.750062)
			(size 0.2286 0.2286)
			(layers "F.Cu" "F.Mask" "F.Paste")
			(net "P12V_OCP_OV_2")
		)
		(pad "D4" smd circle
			(at 0 0.750062)
			(size 0.2286 0.2286)
			(layers "F.Cu" "F.Mask" "F.Paste")
			(net "P12V_OCP_V3_2")
		)
		(pad "D5" smd circle
			(at 0.499872 0.750062)
			(size 0.2286 0.2286)
			(layers "F.Cu" "F.Mask" "F.Paste")
			(net "P12V_AUX")
		)
		(pad "D6" smd circle
			(at 0.999998 0.750062)
			(size 0.2286 0.2286)
			(layers "F.Cu" "F.Mask" "F.Paste")
			(net "P12V_OCP_V3_2")
		)
		(pad "D7" smd circle
			(at 1.500124 0.750062)
			(size 0.2286 0.2286)
			(layers "F.Cu" "F.Mask" "F.Paste")
			(net "P12V_OCP_PWRGD_2")
		)
	)
	(footprint ""
		(layer "F.Cu")
		(at 175.82388 -19.548348 180)
		(property "Reference" "PC2238"
			(at 0 0 180)
			(layer "F.SilkS")
			(hide yes)
			(effects
				(font
					(size 1.27 1.27)
				)
			)
		)
		(property "Value" ""
			(at 0 0 180)
			(layer "F.Fab")
			(effects
				(font
					(size 1.27 1.27)
				)
			)
		)
		(duplicate_pad_numbers_are_jumpers no)
		(fp_line
			(start 0.7874 0.4064)
			(end -0.7874 0.4064)
			(stroke
				(width 0.1524)
				(type default)
			)
			(layer "F.SilkS")
		)
		(fp_line
			(start 0.7874 -0.4064)
			(end 0.7874 0.4064)
			(stroke
				(width 0.1524)
				(type default)
			)
			(layer "F.SilkS")
		)
		(fp_line
			(start -0.7874 0.4064)
			(end -0.7874 -0.4064)
			(stroke
				(width 0.1524)
				(type default)
			)
			(layer "F.SilkS")
		)
		(fp_line
			(start -0.7874 -0.4064)
			(end 0.7874 -0.4064)
			(stroke
				(width 0.1524)
				(type default)
			)
			(layer "F.SilkS")
		)
		(fp_line
			(start 0.67945 0.3048)
			(end 0.120396 0.3048)
			(stroke
				(width 0.1)
				(type default)
			)
			(layer "F.Fab")
		)
		(fp_line
			(start 0.67945 -0.3048)
			(end 0.67945 0.3048)
			(stroke
				(width 0.1)
				(type default)
			)
			(layer "F.Fab")
		)
		(fp_line
			(start 0.12065 -0.2794)
			(end 0.12065 -0.3048)
			(stroke
				(width 0.1)
				(type default)
			)
			(layer "F.Fab")
		)
		(fp_line
			(start 0.12065 -0.3048)
			(end 0.67945 -0.3048)
			(stroke
				(width 0.1)
				(type default)
			)
			(layer "F.Fab")
		)
		(fp_line
			(start 0.120396 0.3048)
			(end 0.120396 0.2794)
			(stroke
				(width 0.1)
				(type default)
			)
			(layer "F.Fab")
		)
		(fp_line
			(start 0.120396 0.2794)
			(end -0.12065 0.2794)
			(stroke
				(width 0.1)
				(type default)
			)
			(layer "F.Fab")
		)
		(fp_line
			(start -0.12065 0.3048)
			(end -0.67945 0.3048)
			(stroke
				(width 0.1)
				(type default)
			)
			(layer "F.Fab")
		)
		(fp_line
			(start -0.12065 0.2794)
			(end -0.12065 0.3048)
			(stroke
				(width 0.1)
				(type default)
			)
			(layer "F.Fab")
		)
		(fp_line
			(start -0.12065 -0.2794)
			(end 0.12065 -0.2794)
			(stroke
				(width 0.1)
				(type default)
			)
			(layer "F.Fab")
		)
		(fp_line
			(start -0.12065 -0.305054)
			(end -0.12065 -0.2794)
			(stroke
				(width 0.1)
				(type default)
			)
			(layer "F.Fab")
		)
		(fp_line
			(start -0.67945 0.3048)
			(end -0.67945 -0.305054)
			(stroke
				(width 0.1)
				(type default)
			)
			(layer "F.Fab")
		)
		(fp_line
			(start -0.67945 -0.305054)
			(end -0.12065 -0.305054)
			(stroke
				(width 0.1)
				(type default)
			)
			(layer "F.Fab")
		)
		(pad "1" smd circle
			(at -0.40005 0 180)
			(size 0 0)
			(layers "F.Cu" "F.Mask" "F.Paste")
			(net "P12V_SCM_R")
		)
		(pad "2" smd circle
			(at 0.40005 0 180)
			(size 0 0)
			(layers "F.Cu" "F.Mask" "F.Paste")
			(net "GND")
		)
	)
	(footprint ""
		(layer "F.Cu")
		(at 412.359348 -16.100298 90)
		(property "Reference" "C46"
			(at 0 0 90)
			(layer "F.SilkS")
			(hide yes)
			(effects
				(font
					(size 1.27 1.27)
				)
			)
		)
		(property "Value" ""
			(at 0 0 90)
			(layer "F.Fab")
			(effects
				(font
					(size 1.27 1.27)
				)
			)
		)
		(duplicate_pad_numbers_are_jumpers no)
		(fp_line
			(start 0.299974 -0.150114)
			(end 0.299974 0.150114)
			(stroke
				(width 0.1)
				(type default)
			)
			(layer "F.Fab")
		)
		(fp_line
			(start -0.299974 -0.150114)
			(end 0.299974 -0.150114)
			(stroke
				(width 0.1)
				(type default)
			)
			(layer "F.Fab")
		)
		(fp_line
			(start 0.299974 0.150114)
			(end -0.299974 0.150114)
			(stroke
				(width 0.1)
				(type default)
			)
			(layer "F.Fab")
		)
		(fp_line
			(start -0.299974 0.150114)
			(end -0.299974 -0.150114)
			(stroke
				(width 0.1)
				(type default)
			)
			(layer "F.Fab")
		)
		(pad "1" smd rect
			(at -0.2667 0 90)
			(size 0.3048 0.381)
			(layers "F.Cu" "F.Mask" "F.Paste")
			(net "P5E_CPU0_G3_TX_C_DN<7>")
		)
		(pad "2" smd rect
			(at 0.2667 0 90)
			(size 0.3048 0.381)
			(layers "F.Cu" "F.Mask" "F.Paste")
			(net "P5E_CPU0_G3_TX_DN<7>")
		)
	)
	(footprint ""
		(layer "F.Cu")
		(at 316.507876 -70.098412 90)
		(property "Reference" "D99"
			(at -3.934714 -0.691642 90)
			(unlocked yes)
			(layer "F.SilkS")
			(effects
				(font
					(size 0.7874 0.5842)
					(thickness 0.1524)
				)
				(justify left)
			)
		)
		(property "Value" ""
			(at 0 0 90)
			(layer "F.Fab")
			(effects
				(font
					(size 1.27 1.27)
				)
			)
		)
		(duplicate_pad_numbers_are_jumpers no)
		(fp_line
			(start 1.16078 -0.4826)
			(end 1.16078 0.4826)
			(stroke
				(width 0.1524)
				(type default)
			)
			(layer "F.SilkS")
		)
		(fp_line
			(start 1.03378 -0.4826)
			(end 1.03378 0.4826)
			(stroke
				(width 0.1524)
				(type default)
			)
			(layer "F.SilkS")
		)
		(fp_line
			(start 0.90678 -0.4826)
			(end 0.90678 0.4826)
			(stroke
				(width 0.1524)
				(type default)
			)
			(layer "F.SilkS")
		)
		(fp_line
			(start -0.64008 -0.4826)
			(end 1.16078 -0.4826)
			(stroke
				(width 0.1524)
				(type default)
			)
			(layer "F.SilkS")
		)
		(fp_line
			(start -0.79248 -0.4826)
			(end 1.03378 -0.4826)
			(stroke
				(width 0.1524)
				(type default)
			)
			(layer "F.SilkS")
		)
		(fp_line
			(start -0.89408 -0.4826)
			(end 0.90678 -0.4826)
			(stroke
				(width 0.1524)
				(type default)
			)
			(layer "F.SilkS")
		)
		(fp_line
			(start 1.16078 0.4826)
			(end -0.64008 0.4826)
			(stroke
				(width 0.1524)
				(type default)
			)
			(layer "F.SilkS")
		)
		(fp_line
			(start 1.03378 0.4826)
			(end -0.79248 0.4826)
			(stroke
				(width 0.1524)
				(type default)
			)
			(layer "F.SilkS")
		)
		(fp_line
			(start 0.90678 0.4826)
			(end -0.90678 0.4826)
			(stroke
				(width 0.1524)
				(type default)
			)
			(layer "F.SilkS")
		)
		(fp_line
			(start -0.90678 0.4826)
			(end -0.90678 -0.4699)
			(stroke
				(width 0.1524)
				(type default)
			)
			(layer "F.SilkS")
		)
		(fp_line
			(start 0.499872 -0.249936)
			(end 0.499872 0.249936)
			(stroke
				(width 0.1)
				(type default)
			)
			(layer "F.Fab")
		)
		(fp_line
			(start -0.499872 -0.249936)
			(end 0.499872 -0.249936)
			(stroke
				(width 0.1)
				(type default)
			)
			(layer "F.Fab")
		)
		(fp_line
			(start 0.499872 0.249936)
			(end -0.499872 0.249936)
			(stroke
				(width 0.1)
				(type default)
			)
			(layer "F.Fab")
		)
		(fp_line
			(start -0.499872 0.249936)
			(end -0.499872 -0.249936)
			(stroke
				(width 0.1)
				(type default)
			)
			(layer "F.Fab")
		)
		(pad "A" smd rect
			(at -0.47498 0 90)
			(size 0.6096 0.7112)
			(layers "F.Cu" "F.Mask" "F.Paste")
			(net "LED_P3V3")
		)
		(pad "C" smd rect
			(at 0.47498 0 90)
			(size 0.6096 0.7112)
			(layers "F.Cu" "F.Mask" "F.Paste")
			(net "GND")
		)
	)
	(footprint ""
		(layer "F.Cu")
		(at 96.0628 -416.4076 180)
		(property "Reference" "R1461"
			(at 0 0 180)
			(layer "F.SilkS")
			(hide yes)
			(effects
				(font
					(size 1.27 1.27)
				)
			)
		)
		(property "Value" ""
			(at 0 0 180)
			(layer "F.Fab")
			(effects
				(font
					(size 1.27 1.27)
				)
			)
		)
		(duplicate_pad_numbers_are_jumpers no)
		(fp_line
			(start 0.32512 0.175006)
			(end -0.32512 0.175006)
			(stroke
				(width 0.1)
				(type default)
			)
			(layer "F.Fab")
		)
		(fp_line
			(start 0.32512 -0.175006)
			(end 0.32512 0.175006)
			(stroke
				(width 0.1)
				(type default)
			)
			(layer "F.Fab")
		)
		(fp_line
			(start -0.32512 0.175006)
			(end -0.32512 -0.175006)
			(stroke
				(width 0.1)
				(type default)
			)
			(layer "F.Fab")
		)
		(fp_line
			(start -0.32512 -0.175006)
			(end 0.32512 -0.175006)
			(stroke
				(width 0.1)
				(type default)
			)
			(layer "F.Fab")
		)
		(pad "1" smd rect
			(at -0.2667 0 180)
			(size 0.3048 0.381)
			(layers "F.Cu" "F.Mask" "F.Paste")
			(net "P1V8_CPU1_RT_1D")
		)
		(pad "2" smd rect
			(at 0.2667 0)
			(size 0.3048 0.381)
			(layers "F.Cu" "F.Mask" "F.Paste")
			(net "JTAG_TCK_RT_CPU1_P1")
		)
	)
	(footprint ""
		(layer "F.Cu")
		(at 381.573278 -141.345158 180)
		(property "Reference" "PR5"
			(at 0 0 180)
			(layer "F.SilkS")
			(hide yes)
			(effects
				(font
					(size 1.27 1.27)
				)
			)
		)
		(property "Value" ""
			(at 0 0 180)
			(layer "F.Fab")
			(effects
				(font
					(size 1.27 1.27)
				)
			)
		)
		(duplicate_pad_numbers_are_jumpers no)
		(fp_line
			(start 0.7874 0.4064)
			(end -0.7874 0.4064)
			(stroke
				(width 0.1524)
				(type default)
			)
			(layer "F.SilkS")
		)
		(fp_line
			(start 0.7874 -0.4064)
			(end 0.7874 0.4064)
			(stroke
				(width 0.1524)
				(type default)
			)
			(layer "F.SilkS")
		)
		(fp_line
			(start -0.7874 0.4064)
			(end -0.7874 -0.4064)
			(stroke
				(width 0.1524)
				(type default)
			)
			(layer "F.SilkS")
		)
		(fp_line
			(start -0.7874 -0.4064)
			(end 0.7874 -0.4064)
			(stroke
				(width 0.1524)
				(type default)
			)
			(layer "F.SilkS")
		)
		(fp_line
			(start 0.67945 0.3048)
			(end 0.120396 0.3048)
			(stroke
				(width 0.1)
				(type default)
			)
			(layer "F.Fab")
		)
		(fp_line
			(start 0.67945 -0.3048)
			(end 0.67945 0.3048)
			(stroke
				(width 0.1)
				(type default)
			)
			(layer "F.Fab")
		)
		(fp_line
			(start 0.12065 -0.2794)
			(end 0.12065 -0.3048)
			(stroke
				(width 0.1)
				(type default)
			)
			(layer "F.Fab")
		)
		(fp_line
			(start 0.12065 -0.3048)
			(end 0.67945 -0.3048)
			(stroke
				(width 0.1)
				(type default)
			)
			(layer "F.Fab")
		)
		(fp_line
			(start 0.120396 0.3048)
			(end 0.120396 0.2794)
			(stroke
				(width 0.1)
				(type default)
			)
			(layer "F.Fab")
		)
		(fp_line
			(start 0.120396 0.2794)
			(end -0.12065 0.2794)
			(stroke
				(width 0.1)
				(type default)
			)
			(layer "F.Fab")
		)
		(fp_line
			(start -0.12065 0.3048)
			(end -0.67945 0.3048)
			(stroke
				(width 0.1)
				(type default)
			)
			(layer "F.Fab")
		)
		(fp_line
			(start -0.12065 0.2794)
			(end -0.12065 0.3048)
			(stroke
				(width 0.1)
				(type default)
			)
			(layer "F.Fab")
		)
		(fp_line
			(start -0.12065 -0.2794)
			(end 0.12065 -0.2794)
			(stroke
				(width 0.1)
				(type default)
			)
			(layer "F.Fab")
		)
		(fp_line
			(start -0.12065 -0.305054)
			(end -0.12065 -0.2794)
			(stroke
				(width 0.1)
				(type default)
			)
			(layer "F.Fab")
		)
		(fp_line
			(start -0.67945 0.3048)
			(end -0.67945 -0.305054)
			(stroke
				(width 0.1)
				(type default)
			)
			(layer "F.Fab")
		)
		(fp_line
			(start -0.67945 -0.305054)
			(end -0.12065 -0.305054)
			(stroke
				(width 0.1)
				(type default)
			)
			(layer "F.Fab")
		)
		(pad "1" smd circle
			(at -0.40005 0 180)
			(size 0 0)
			(layers "F.Cu" "F.Mask" "F.Paste")
			(net "PVDDCR_CPU0_P0_VMON")
		)
		(pad "2" smd circle
			(at 0.40005 0 180)
			(size 0 0)
			(layers "F.Cu" "F.Mask" "F.Paste")
			(net "GND")
		)
	)
)
